(kicad_pcb
	(version 20241229)
	(generator "pcbnew")
	(generator_version "9.0")
	(general
		(thickness 1.62)
		(legacy_teardrops no)
	)
	(paper "A3")
	(title_block
		(title "COM Express 7 Baseboard")
		(date "2025-02-04")
		(rev "1.1.2")
		(company "Antmicro Ltd")
		(comment 1 "www.antmicro.com")
		(comment 9 "footprint 631 of 802 (U39), pads 1-42 of 57")
	)
	(layers
		(0 "F.Cu" signal)
		(4 "In1.Cu" signal)
		(6 "In2.Cu" signal)
		(8 "In3.Cu" signal)
		(10 "In4.Cu" signal)
		(12 "In5.Cu" signal)
		(14 "In6.Cu" signal)
		(2 "B.Cu" signal)
		(9 "F.Adhes" user "F.Adhesive")
		(11 "B.Adhes" user "B.Adhesive")
		(13 "F.Paste" user)
		(15 "B.Paste" user)
		(5 "F.SilkS" user "F.Silkscreen")
		(7 "B.SilkS" user "B.Silkscreen")
		(1 "F.Mask" user)
		(3 "B.Mask" user)
		(17 "Dwgs.User" user "User.Drawings")
		(19 "Cmts.User" user "User.Comments")
		(21 "Eco1.User" user "User.Eco1")
		(23 "Eco2.User" user "User.Eco2")
		(25 "Edge.Cuts" user)
		(27 "Margin" user)
		(31 "F.CrtYd" user "F.Courtyard")
		(29 "B.CrtYd" user "B.Courtyard")
		(35 "F.Fab" user)
		(33 "B.Fab" user)
	)
	(footprint "antmicro-footprints:WQFN-42-1EP_3.5x9mm_P0.5mm"
		(layer "B.Cu")
		(at 117.401 147.361 -90)
		(descr "WQFN, 42 Pin (http://www.ti.com/lit/ds/symlink/ts3l501e.pdf#page=23), generated with kicad-footprint-generator ipc_noLead_generator.py")
		(tags "WQFN NoLead")
		(property "Reference" "U39"
			(at -2.301 5.001 90)
			(layer "B.SilkS")
			(effects
				(font
					(size 0.7 0.7)
					(thickness 0.15)
				)
				(justify left bottom mirror)
			)
		)
		(property "Value" "PI3EQX16904GL"
			(at 0 -5.82 90)
			(layer "B.Fab")
			(effects
				(font
					(size 0.7 0.7)
					(thickness 0.15)
				)
				(justify left bottom mirror)
			)
		)
		(property "Datasheet" "https://www.diodes.com/part/view/PI3EQX16904GL"
			(at 0 0 270)
			(layer "F.Fab")
			(hide yes)
			(effects
				(font
					(size 1.27 1.27)
					(thickness 0.15)
				)
			)
		)
		(property "Author" "Antmicro"
			(at -29.96 264.762 0)
			(layer "B.Fab")
			(hide yes)
			(effects
				(font
					(size 1 1)
					(thickness 0.15)
				)
				(justify mirror)
			)
		)
		(property "License" "Apache-2.0"
			(at -29.96 264.762 0)
			(layer "B.Fab")
			(hide yes)
			(effects
				(font
					(size 1 1)
					(thickness 0.15)
				)
				(justify mirror)
			)
		)
		(property "MPN" "PI3EQX16904GLZHEX"
			(at -29.96 264.762 0)
			(layer "B.Fab")
			(hide yes)
			(effects
				(font
					(size 1 1)
					(thickness 0.15)
				)
				(justify mirror)
			)
		)
		(property "Manufacturer" "Diodes Incorporated"
			(at -29.96 264.762 0)
			(layer "B.Fab")
			(hide yes)
			(effects
				(font
					(size 1 1)
					(thickness 0.15)
				)
				(justify mirror)
			)
		)
		(sheetname "PCIe redriver")
		(sheetfile "pcie_redriver.kicad_sch")
		(attr smd)
		(pad "" smd roundrect
			(at -0.51 -3.24 270)
			(size 0.83 0.87)
			(layers "B.Paste")
			(roundrect_rratio 0.25)
			(teardrops
				(best_length_ratio 0.2)
				(max_length 1)
				(best_width_ratio 0.9)
				(max_width 2)
				(curved_edges yes)
				(filter_ratio 0.9)
				(enabled yes)
				(allow_two_segments yes)
				(prefer_zone_connections yes)
			)
		)
		(pad "" smd roundrect
			(at -0.51 -2.16 270)
			(size 0.83 0.87)
			(layers "B.Paste")
			(roundrect_rratio 0.25)
			(teardrops
				(best_length_ratio 0.2)
				(max_length 1)
				(best_width_ratio 0.9)
				(max_width 2)
				(curved_edges yes)
				(filter_ratio 0.9)
				(enabled yes)
				(allow_two_segments yes)
				(prefer_zone_connections yes)
			)
		)
		(pad "" smd roundrect
			(at -0.51 -1.08 270)
			(size 0.83 0.87)
			(layers "B.Paste")
			(roundrect_rratio 0.25)
			(teardrops
				(best_length_ratio 0.2)
				(max_length 1)
				(best_width_ratio 0.9)
				(max_width 2)
				(curved_edges yes)
				(filter_ratio 0.9)
				(enabled yes)
				(allow_two_segments yes)
				(prefer_zone_connections yes)
			)
		)
		(pad "" smd roundrect
			(at -0.51 0 270)
			(size 0.83 0.87)
			(layers "B.Paste")
			(roundrect_rratio 0.25)
			(teardrops
				(best_length_ratio 0.2)
				(max_length 1)
				(best_width_ratio 0.9)
				(max_width 2)
				(curved_edges yes)
				(filter_ratio 0.9)
				(enabled yes)
				(allow_two_segments yes)
				(prefer_zone_connections yes)
			)
		)
		(pad "" smd roundrect
			(at -0.51 1.081 270)
			(size 0.83 0.87)
			(layers "B.Paste")
			(roundrect_rratio 0.25)
			(teardrops
				(best_length_ratio 0.2)
				(max_length 1)
				(best_width_ratio 0.9)
				(max_width 2)
				(curved_edges yes)
				(filter_ratio 0.9)
				(enabled yes)
				(allow_two_segments yes)
				(prefer_zone_connections yes)
			)
		)
		(pad "" smd roundrect
			(at -0.51 2.161 270)
			(size 0.83 0.87)
			(layers "B.Paste")
			(roundrect_rratio 0.25)
			(teardrops
				(best_length_ratio 0.2)
				(max_length 1)
				(best_width_ratio 0.9)
				(max_width 2)
				(curved_edges yes)
				(filter_ratio 0.9)
				(enabled yes)
				(allow_two_segments yes)
				(prefer_zone_connections yes)
			)
		)
		(pad "" smd roundrect
			(at -0.51 3.242 270)
			(size 0.83 0.87)
			(layers "B.Paste")
			(roundrect_rratio 0.25)
			(teardrops
				(best_length_ratio 0.2)
				(max_length 1)
				(best_width_ratio 0.9)
				(max_width 2)
				(curved_edges yes)
				(filter_ratio 0.9)
				(enabled yes)
				(allow_two_segments yes)
				(prefer_zone_connections yes)
			)
		)
		(pad "" smd roundrect
			(at 0.508 -3.24 270)
			(size 0.83 0.87)
			(layers "B.Paste")
			(roundrect_rratio 0.25)
			(teardrops
				(best_length_ratio 0.2)
				(max_length 1)
				(best_width_ratio 0.9)
				(max_width 2)
				(curved_edges yes)
				(filter_ratio 0.9)
				(enabled yes)
				(allow_two_segments yes)
				(prefer_zone_connections yes)
			)
		)
		(pad "" smd roundrect
			(at 0.508 -2.16 270)
			(size 0.83 0.87)
			(layers "B.Paste")
			(roundrect_rratio 0.25)
			(teardrops
				(best_length_ratio 0.2)
				(max_length 1)
				(best_width_ratio 0.9)
				(max_width 2)
				(curved_edges yes)
				(filter_ratio 0.9)
				(enabled yes)
				(allow_two_segments yes)
				(prefer_zone_connections yes)
			)
		)
		(pad "" smd roundrect
			(at 0.508 -1.08 270)
			(size 0.83 0.87)
			(layers "B.Paste")
			(roundrect_rratio 0.25)
			(teardrops
				(best_length_ratio 0.2)
				(max_length 1)
				(best_width_ratio 0.9)
				(max_width 2)
				(curved_edges yes)
				(filter_ratio 0.9)
				(enabled yes)
				(allow_two_segments yes)
				(prefer_zone_connections yes)
			)
		)
		(pad "" smd roundrect
			(at 0.508 0 270)
			(size 0.83 0.87)
			(layers "B.Paste")
			(roundrect_rratio 0.25)
			(teardrops
				(best_length_ratio 0.2)
				(max_length 1)
				(best_width_ratio 0.9)
				(max_width 2)
				(curved_edges yes)
				(filter_ratio 0.9)
				(enabled yes)
				(allow_two_segments yes)
				(prefer_zone_connections yes)
			)
		)
		(pad "" smd roundrect
			(at 0.508 1.081 270)
			(size 0.83 0.87)
			(layers "B.Paste")
			(roundrect_rratio 0.25)
			(teardrops
				(best_length_ratio 0.2)
				(max_length 1)
				(best_width_ratio 0.9)
				(max_width 2)
				(curved_edges yes)
				(filter_ratio 0.9)
				(enabled yes)
				(allow_two_segments yes)
				(prefer_zone_connections yes)
			)
		)
		(pad "" smd roundrect
			(at 0.508 2.161 270)
			(size 0.83 0.87)
			(layers "B.Paste")
			(roundrect_rratio 0.25)
			(teardrops
				(best_length_ratio 0.2)
				(max_length 1)
				(best_width_ratio 0.9)
				(max_width 2)
				(curved_edges yes)
				(filter_ratio 0.9)
				(enabled yes)
				(allow_two_segments yes)
				(prefer_zone_connections yes)
			)
		)
		(pad "" smd roundrect
			(at 0.508 3.242 270)
			(size 0.83 0.87)
			(layers "B.Paste")
			(roundrect_rratio 0.25)
			(teardrops
				(best_length_ratio 0.2)
				(max_length 1)
				(best_width_ratio 0.9)
				(max_width 2)
				(curved_edges yes)
				(filter_ratio 0.9)
				(enabled yes)
				(allow_two_segments yes)
				(prefer_zone_connections yes)
			)
		)
		(pad "1" smd roundrect
			(at -1.688 4 270)
			(size 0.875 0.25)
			(layers "B.Cu" "B.Mask" "B.Paste")
			(roundrect_rratio 0.25)
			(net 625 "/PCIe redriver/TX_EQ2")
			(pinfunction "EQ2")
			(pintype "passive")
			(teardrops
				(best_length_ratio 0.2)
				(max_length 1)
				(best_width_ratio 0.9)
				(max_width 2)
				(curved_edges yes)
				(filter_ratio 0.9)
				(enabled yes)
				(allow_two_segments yes)
				(prefer_zone_connections yes)
			)
		)
		(pad "2" smd roundrect
			(at -1.688 3.5 270)
			(size 0.875 0.25)
			(layers "B.Cu" "B.Mask" "B.Paste")
			(roundrect_rratio 0.25)
			(net 628 "/PCIe redriver/TX_SW")
			(pinfunction "SW1")
			(pintype "input")
			(teardrops
				(best_length_ratio 0.2)
				(max_length 1)
				(best_width_ratio 0.9)
				(max_width 2)
				(curved_edges yes)
				(filter_ratio 0.9)
				(enabled yes)
				(allow_two_segments yes)
				(prefer_zone_connections yes)
			)
		)
		(pad "3" smd roundrect
			(at -1.688 3 270)
			(size 0.875 0.25)
			(layers "B.Cu" "B.Mask" "B.Paste")
			(roundrect_rratio 0.25)
			(net 2 "+3V3")
			(pinfunction "VCC")
			(pintype "passive")
			(teardrops
				(best_length_ratio 0.2)
				(max_length 1)
				(best_width_ratio 0.9)
				(max_width 2)
				(curved_edges yes)
				(filter_ratio 0.9)
				(enabled yes)
				(allow_two_segments yes)
				(prefer_zone_connections yes)
			)
		)
		(pad "4" smd roundrect
			(at -1.688 2.5 270)
			(size 0.875 0.25)
			(layers "B.Cu" "B.Mask" "B.Paste")
			(roundrect_rratio 0.25)
			(net 211 "/Com Express 7 Interfaces/PCIe_{B1x4}.TX3-")
			(pinfunction "A0RX+")
			(pintype "input")
			(teardrops
				(best_length_ratio 0.2)
				(max_length 1)
				(best_width_ratio 0.9)
				(max_width 2)
				(curved_edges yes)
				(filter_ratio 0.9)
				(enabled yes)
				(allow_two_segments yes)
				(prefer_zone_connections yes)
			)
		)
		(pad "5" smd roundrect
			(at -1.688 2 270)
			(size 0.875 0.25)
			(layers "B.Cu" "B.Mask" "B.Paste")
			(roundrect_rratio 0.25)
			(net 212 "/Com Express 7 Interfaces/PCIe_{B1x4}.TX3+")
			(pinfunction "A0RX-")
			(pintype "input")
			(teardrops
				(best_length_ratio 0.2)
				(max_length 1)
				(best_width_ratio 0.9)
				(max_width 2)
				(curved_edges yes)
				(filter_ratio 0.9)
				(enabled yes)
				(allow_two_segments yes)
				(prefer_zone_connections yes)
			)
		)
		(pad "6" smd roundrect
			(at -1.688 1.5 270)
			(size 0.875 0.25)
			(layers "B.Cu" "B.Mask" "B.Paste")
			(roundrect_rratio 0.25)
			(net 2 "+3V3")
			(pinfunction "VCC")
			(pintype "passive")
			(teardrops
				(best_length_ratio 0.2)
				(max_length 1)
				(best_width_ratio 0.9)
				(max_width 2)
				(curved_edges yes)
				(filter_ratio 0.9)
				(enabled yes)
				(allow_two_segments yes)
				(prefer_zone_connections yes)
			)
		)
		(pad "7" smd roundrect
			(at -1.688 1 270)
			(size 0.875 0.25)
			(layers "B.Cu" "B.Mask" "B.Paste")
			(roundrect_rratio 0.25)
			(net 215 "/Com Express 7 Interfaces/PCIe_{B1x4}.TX2-")
			(pinfunction "A1RX+")
			(pintype "input")
			(teardrops
				(best_length_ratio 0.2)
				(max_length 1)
				(best_width_ratio 0.9)
				(max_width 2)
				(curved_edges yes)
				(filter_ratio 0.9)
				(enabled yes)
				(allow_two_segments yes)
				(prefer_zone_connections yes)
			)
		)
		(pad "8" smd roundrect
			(at -1.688 0.5 270)
			(size 0.875 0.25)
			(layers "B.Cu" "B.Mask" "B.Paste")
			(roundrect_rratio 0.25)
			(net 216 "/Com Express 7 Interfaces/PCIe_{B1x4}.TX2+")
			(pinfunction "A1RX-")
			(pintype "input")
			(teardrops
				(best_length_ratio 0.2)
				(max_length 1)
				(best_width_ratio 0.9)
				(max_width 2)
				(curved_edges yes)
				(filter_ratio 0.9)
				(enabled yes)
				(allow_two_segments yes)
				(prefer_zone_connections yes)
			)
		)
		(pad "9" smd roundrect
			(at -1.688 0 270)
			(size 0.875 0.25)
			(layers "B.Cu" "B.Mask" "B.Paste")
			(roundrect_rratio 0.25)
			(net 2 "+3V3")
			(pinfunction "VCC")
			(pintype "passive")
			(teardrops
				(best_length_ratio 0.2)
				(max_length 1)
				(best_width_ratio 0.9)
				(max_width 2)
				(curved_edges yes)
				(filter_ratio 0.9)
				(enabled yes)
				(allow_two_segments yes)
				(prefer_zone_connections yes)
			)
		)
		(pad "10" smd roundrect
			(at -1.688 -0.5 270)
			(size 0.875 0.25)
			(layers "B.Cu" "B.Mask" "B.Paste")
			(roundrect_rratio 0.25)
			(net 219 "/Com Express 7 Interfaces/PCIe_{B1x4}.TX1-")
			(pinfunction "A2RX+")
			(pintype "input")
			(teardrops
				(best_length_ratio 0.2)
				(max_length 1)
				(best_width_ratio 0.9)
				(max_width 2)
				(curved_edges yes)
				(filter_ratio 0.9)
				(enabled yes)
				(allow_two_segments yes)
				(prefer_zone_connections yes)
			)
		)
		(pad "11" smd roundrect
			(at -1.688 -1 270)
			(size 0.875 0.25)
			(layers "B.Cu" "B.Mask" "B.Paste")
			(roundrect_rratio 0.25)
			(net 220 "/Com Express 7 Interfaces/PCIe_{B1x4}.TX1+")
			(pinfunction "A2RX-")
			(pintype "input")
			(teardrops
				(best_length_ratio 0.2)
				(max_length 1)
				(best_width_ratio 0.9)
				(max_width 2)
				(curved_edges yes)
				(filter_ratio 0.9)
				(enabled yes)
				(allow_two_segments yes)
				(prefer_zone_connections yes)
			)
		)
		(pad "12" smd roundrect
			(at -1.688 -1.5 270)
			(size 0.875 0.25)
			(layers "B.Cu" "B.Mask" "B.Paste")
			(roundrect_rratio 0.25)
			(net 2 "+3V3")
			(pinfunction "VCC")
			(pintype "power_in")
			(teardrops
				(best_length_ratio 0.2)
				(max_length 1)
				(best_width_ratio 0.9)
				(max_width 2)
				(curved_edges yes)
				(filter_ratio 0.9)
				(enabled yes)
				(allow_two_segments yes)
				(prefer_zone_connections yes)
			)
		)
		(pad "13" smd roundrect
			(at -1.688 -2 270)
			(size 0.875 0.25)
			(layers "B.Cu" "B.Mask" "B.Paste")
			(roundrect_rratio 0.25)
			(net 225 "/Com Express 7 Interfaces/PCIe_{B1x4}.TX0-")
			(pinfunction "A3RX+")
			(pintype "input")
			(teardrops
				(best_length_ratio 0.2)
				(max_length 1)
				(best_width_ratio 0.9)
				(max_width 2)
				(curved_edges yes)
				(filter_ratio 0.9)
				(enabled yes)
				(allow_two_segments yes)
				(prefer_zone_connections yes)
			)
		)
		(pad "14" smd roundrect
			(at -1.688 -2.5 270)
			(size 0.875 0.25)
			(layers "B.Cu" "B.Mask" "B.Paste")
			(roundrect_rratio 0.25)
			(net 227 "/Com Express 7 Interfaces/PCIe_{B1x4}.TX0+")
			(pinfunction "A3RX-")
			(pintype "input")
			(teardrops
				(best_length_ratio 0.2)
				(max_length 1)
				(best_width_ratio 0.9)
				(max_width 2)
				(curved_edges yes)
				(filter_ratio 0.9)
				(enabled yes)
				(allow_two_segments yes)
				(prefer_zone_connections yes)
			)
		)
		(pad "15" smd roundrect
			(at -1.688 -3 270)
			(size 0.875 0.25)
			(layers "B.Cu" "B.Mask" "B.Paste")
			(roundrect_rratio 0.25)
			(net 2 "+3V3")
			(pinfunction "VCC")
			(pintype "passive")
			(teardrops
				(best_length_ratio 0.2)
				(max_length 1)
				(best_width_ratio 0.9)
				(max_width 2)
				(curved_edges yes)
				(filter_ratio 0.9)
				(enabled yes)
				(allow_two_segments yes)
				(prefer_zone_connections yes)
			)
		)
		(pad "16" smd roundrect
			(at -1.688 -3.5 270)
			(size 0.875 0.25)
			(layers "B.Cu" "B.Mask" "B.Paste")
			(roundrect_rratio 0.25)
			(net 715 "Net-(U39-~{I2C_{RESET}})")
			(pinfunction "~{I2C_{RESET}}")
			(pintype "input")
			(teardrops
				(best_length_ratio 0.2)
				(max_length 1)
				(best_width_ratio 0.9)
				(max_width 2)
				(curved_edges yes)
				(filter_ratio 0.9)
				(enabled yes)
				(allow_two_segments yes)
				(prefer_zone_connections yes)
			)
		)
		(pad "17" smd roundrect
			(at -1.688 -4 270)
			(size 0.875 0.25)
			(layers "B.Cu" "B.Mask" "B.Paste")
			(roundrect_rratio 0.25)
			(net 1 "GND")
			(pinfunction "AD1")
			(pintype "passive")
			(teardrops
				(best_length_ratio 0.2)
				(max_length 1)
				(best_width_ratio 0.9)
				(max_width 2)
				(curved_edges yes)
				(filter_ratio 0.9)
				(enabled yes)
				(allow_two_segments yes)
				(prefer_zone_connections yes)
			)
		)
		(pad "18" smd roundrect
			(at -0.75 -4.437 270)
			(size 0.25 0.875)
			(layers "B.Cu" "B.Mask" "B.Paste")
			(roundrect_rratio 0.25)
			(net 712 "Net-(U39-SDA)")
			(pinfunction "SDA")
			(pintype "open_collector")
			(teardrops
				(best_length_ratio 0.2)
				(max_length 1)
				(best_width_ratio 0.9)
				(max_width 2)
				(curved_edges yes)
				(filter_ratio 0.9)
				(enabled yes)
				(allow_two_segments yes)
				(prefer_zone_connections yes)
			)
		)
		(pad "19" smd roundrect
			(at -0.25 -4.437 270)
			(size 0.25 0.875)
			(layers "B.Cu" "B.Mask" "B.Paste")
			(roundrect_rratio 0.25)
			(net 713 "Net-(U39-SCL)")
			(pinfunction "SCL")
			(pintype "open_collector")
			(teardrops
				(best_length_ratio 0.2)
				(max_length 1)
				(best_width_ratio 0.9)
				(max_width 2)
				(curved_edges yes)
				(filter_ratio 0.9)
				(enabled yes)
				(allow_two_segments yes)
				(prefer_zone_connections yes)
			)
		)
		(pad "20" smd roundrect
			(at 0.25 -4.437 270)
			(size 0.25 0.875)
			(layers "B.Cu" "B.Mask" "B.Paste")
			(roundrect_rratio 0.25)
			(net 945 "/GPIO expander/GPIOEX5")
			(pinfunction "~{PRSNT}")
			(pintype "input")
			(teardrops
				(best_length_ratio 0.2)
				(max_length 1)
				(best_width_ratio 0.9)
				(max_width 2)
				(curved_edges yes)
				(filter_ratio 0.9)
				(enabled yes)
				(allow_two_segments yes)
				(prefer_zone_connections yes)
			)
		)
		(pad "21" smd roundrect
			(at 0.75 -4.437 270)
			(size 0.25 0.875)
			(layers "B.Cu" "B.Mask" "B.Paste")
			(roundrect_rratio 0.25)
			(net 629 "Net-(U39-EN_{I2C})")
			(pinfunction "EN_{I2C}")
			(pintype "input")
			(teardrops
				(best_length_ratio 0.2)
				(max_length 1)
				(best_width_ratio 0.9)
				(max_width 2)
				(curved_edges yes)
				(filter_ratio 0.9)
				(enabled yes)
				(allow_two_segments yes)
				(prefer_zone_connections yes)
			)
		)
		(pad "22" smd roundrect
			(at 1.687 -4 270)
			(size 0.875 0.25)
			(layers "B.Cu" "B.Mask" "B.Paste")
			(roundrect_rratio 0.25)
			(net 714 "Net-(U39-I2C_{DONE})")
			(pinfunction "I2C_{DONE}")
			(pintype "input")
			(teardrops
				(best_length_ratio 0.2)
				(max_length 1)
				(best_width_ratio 0.9)
				(max_width 2)
				(curved_edges yes)
				(filter_ratio 0.9)
				(enabled yes)
				(allow_two_segments yes)
				(prefer_zone_connections yes)
			)
		)
		(pad "23" smd roundrect
			(at 1.687 -3.5 270)
			(size 0.875 0.25)
			(layers "B.Cu" "B.Mask" "B.Paste")
			(roundrect_rratio 0.25)
			(net 631 "Net-(U39-RXDET)")
			(pinfunction "RXDET")
			(pintype "input")
			(teardrops
				(best_length_ratio 0.2)
				(max_length 1)
				(best_width_ratio 0.9)
				(max_width 2)
				(curved_edges yes)
				(filter_ratio 0.9)
				(enabled yes)
				(allow_two_segments yes)
				(prefer_zone_connections yes)
			)
		)
		(pad "24" smd roundrect
			(at 1.687 -3 270)
			(size 0.875 0.25)
			(layers "B.Cu" "B.Mask" "B.Paste")
			(roundrect_rratio 0.25)
			(net 2 "+3V3")
			(pinfunction "VCC")
			(pintype "passive")
			(teardrops
				(best_length_ratio 0.2)
				(max_length 1)
				(best_width_ratio 0.9)
				(max_width 2)
				(curved_edges yes)
				(filter_ratio 0.9)
				(enabled yes)
				(allow_two_segments yes)
				(prefer_zone_connections yes)
			)
		)
		(pad "25" smd roundrect
			(at 1.687 -2.5 270)
			(size 0.875 0.25)
			(layers "B.Cu" "B.Mask" "B.Paste")
			(roundrect_rratio 0.25)
			(net 963 "/PCIe redriver/PCIe_{O}_C.TX0+")
			(pinfunction "A3TX-")
			(pintype "output")
			(teardrops
				(best_length_ratio 0.2)
				(max_length 1)
				(best_width_ratio 0.9)
				(max_width 2)
				(curved_edges yes)
				(filter_ratio 0.9)
				(enabled yes)
				(allow_two_segments yes)
				(prefer_zone_connections yes)
			)
		)
		(pad "26" smd roundrect
			(at 1.687 -2 270)
			(size 0.875 0.25)
			(layers "B.Cu" "B.Mask" "B.Paste")
			(roundrect_rratio 0.25)
			(net 966 "/PCIe redriver/PCIe_{O}_C.TX0-")
			(pinfunction "A3TX+")
			(pintype "input")
			(teardrops
				(best_length_ratio 0.2)
				(max_length 1)
				(best_width_ratio 0.9)
				(max_width 2)
				(curved_edges yes)
				(filter_ratio 0.9)
				(enabled yes)
				(allow_two_segments yes)
				(prefer_zone_connections yes)
			)
		)
		(pad "27" smd roundrect
			(at 1.687 -1.5 270)
			(size 0.875 0.25)
			(layers "B.Cu" "B.Mask" "B.Paste")
			(roundrect_rratio 0.25)
			(net 2 "+3V3")
			(pinfunction "VCC")
			(pintype "passive")
			(teardrops
				(best_length_ratio 0.2)
				(max_length 1)
				(best_width_ratio 0.9)
				(max_width 2)
				(curved_edges yes)
				(filter_ratio 0.9)
				(enabled yes)
				(allow_two_segments yes)
				(prefer_zone_connections yes)
			)
		)
		(pad "28" smd roundrect
			(at 1.687 -1 270)
			(size 0.875 0.25)
			(layers "B.Cu" "B.Mask" "B.Paste")
			(roundrect_rratio 0.25)
			(net 962 "/PCIe redriver/PCIe_{O}_C.TX1+")
			(pinfunction "A2TX-")
			(pintype "output")
			(teardrops
				(best_length_ratio 0.2)
				(max_length 1)
				(best_width_ratio 0.9)
				(max_width 2)
				(curved_edges yes)
				(filter_ratio 0.9)
				(enabled yes)
				(allow_two_segments yes)
				(prefer_zone_connections yes)
			)
		)
	)
)
